(kicad_pcb
	(version 20241229)
	(generator "pcbnew")
	(generator_version "9.0")
	(general
		(thickness 1.61)
		(legacy_teardrops no)
	)
	(paper "A3")
	(title_block
		(title "RDIMM DDR5 Tester")
		(date "2026-05-21")
		(rev "2.2.0")
		(company "Antmicro")
		(comment 9 "footprints 402-406 of 796")
	)
	(layers
		(0 "F.Cu" signal)
		(4 "In1.Cu" power)
		(6 "In2.Cu" mixed)
		(8 "In3.Cu" power)
		(10 "In4.Cu" mixed)
		(12 "In5.Cu" power)
		(14 "In6.Cu" mixed)
		(16 "In7.Cu" power)
		(18 "In8.Cu" power)
		(20 "In9.Cu" mixed)
		(22 "In10.Cu" power)
		(2 "B.Cu" signal)
		(9 "F.Adhes" user "F.Adhesive")
		(11 "B.Adhes" user "B.Adhesive")
		(13 "F.Paste" user)
		(15 "B.Paste" user)
		(5 "F.SilkS" user "F.Silkscreen")
		(7 "B.SilkS" user "B.Silkscreen")
		(1 "F.Mask" user)
		(3 "B.Mask" user)
		(17 "Dwgs.User" user "User.Drawings")
		(19 "Cmts.User" user "User.Comments")
		(21 "Eco1.User" user "User.Eco1")
		(23 "Eco2.User" user "User.Eco2")
		(25 "Edge.Cuts" user)
		(27 "Margin" user)
		(31 "F.CrtYd" user "F.Courtyard")
		(29 "B.CrtYd" user "B.Courtyard")
		(35 "F.Fab" user)
		(33 "B.Fab" user)
	)
	(footprint "antmicro-footprints:C_0402_1005Metric"
		(layer "B.Cu")
		(at 139.011328 139.257157)
		(descr "Capacitor SMD 0402")
		(tags "capacitor SMD 0402")
		(property "Reference" "C152"
			(at 1.450672 0.442843 0)
			(layer "B.SilkS")
			(effects
				(font
					(size 0.7 0.7)
					(thickness 0.15)
				)
				(justify right bottom mirror)
			)
		)
		(property "Value" "C_4u7_0402"
			(at -1.022927 -2.155213 0)
			(layer "B.Fab")
			(effects
				(font
					(size 0.7 0.7)
					(thickness 0.15)
				)
				(justify right bottom mirror)
			)
		)
		(property "Datasheet" "https://www.murata.com/products/productdetail?partno=GRM155R61A475MEAA%23"
			(at 0 0 0)
			(layer "F.Fab")
			(hide yes)
			(effects
				(font
					(size 1.27 1.27)
					(thickness 0.15)
				)
			)
		)
		(property "Manufacturer" "Murata"
			(at 0 0 0)
			(unlocked yes)
			(layer "B.Fab")
			(hide yes)
			(effects
				(font
					(size 1 1)
					(thickness 0.15)
				)
				(justify mirror)
			)
		)
		(property "MPN" "GRM155R61A475MEAAD"
			(at 0 0 0)
			(unlocked yes)
			(layer "B.Fab")
			(hide yes)
			(effects
				(font
					(size 1 1)
					(thickness 0.15)
				)
				(justify mirror)
			)
		)
		(property "Val" "4u7"
			(at 0 0 0)
			(unlocked yes)
			(layer "B.Fab")
			(hide yes)
			(effects
				(font
					(size 1 1)
					(thickness 0.15)
				)
				(justify mirror)
			)
		)
		(property "License" "Apache-2.0"
			(at 0 0 0)
			(unlocked yes)
			(layer "B.Fab")
			(hide yes)
			(effects
				(font
					(size 1 1)
					(thickness 0.15)
				)
				(justify mirror)
			)
		)
		(property "Author" "Antmicro"
			(at 0 0 0)
			(unlocked yes)
			(layer "B.Fab")
			(hide yes)
			(effects
				(font
					(size 1 1)
					(thickness 0.15)
				)
				(justify mirror)
			)
		)
		(property "Voltage" ""
			(at 0 0 0)
			(unlocked yes)
			(layer "B.Fab")
			(hide yes)
			(effects
				(font
					(size 1 1)
					(thickness 0.15)
				)
				(justify mirror)
			)
		)
		(property "Dielectric" ""
			(at 0 0 0)
			(unlocked yes)
			(layer "B.Fab")
			(hide yes)
			(effects
				(font
					(size 1 1)
					(thickness 0.15)
				)
				(justify mirror)
			)
		)
		(sheetname "/Ethernet/")
		(sheetfile "ethernet.kicad_sch")
		(attr smd)
		(fp_rect
			(start -0.925 0.47)
			(end 0.925 -0.47)
			(stroke
				(width 0.05)
				(type default)
			)
			(fill no)
			(layer "B.CrtYd")
		)
		(fp_line
			(start -0.494 -0.248)
			(end -0.494 0.25)
			(stroke
				(width 0.15)
				(type solid)
			)
			(layer "B.Fab")
		)
		(fp_line
			(start -0.494 0.25)
			(end 0.504 0.25)
			(stroke
				(width 0.15)
				(type solid)
			)
			(layer "B.Fab")
		)
		(fp_line
			(start 0.504 -0.248)
			(end -0.494 -0.248)
			(stroke
				(width 0.15)
				(type solid)
			)
			(layer "B.Fab")
		)
		(fp_line
			(start 0.504 0.25)
			(end 0.504 -0.248)
			(stroke
				(width 0.15)
				(type solid)
			)
			(layer "B.Fab")
		)
		(fp_text user "${REFERENCE}"
			(at -0.939 -4.599 180)
			(layer "B.Fab")
			(effects
				(font
					(size 0.7 0.7)
					(thickness 0.15)
				)
				(justify left bottom mirror)
			)
		)
		(fp_text user "Author: Antmicro"
			(at -0.939 -3.399 180)
			(layer "B.Fab")
			(effects
				(font
					(size 0.7 0.7)
					(thickness 0.15)
				)
				(justify left bottom mirror)
			)
		)
		(fp_text user "License: Apache-2.0"
			(at -0.939 -5.799 180)
			(layer "B.Fab")
			(effects
				(font
					(size 0.7 0.7)
					(thickness 0.15)
				)
				(justify left bottom mirror)
			)
		)
		(pad "1" smd roundrect
			(at -0.48 0)
			(size 0.59 0.64)
			(layers "B.Cu" "B.Mask" "B.Paste")
			(roundrect_rratio 0.25)
			(net 97 "/Ethernet/AVDDH")
			(pintype "passive")
		)
		(pad "2" smd roundrect
			(at 0.48 0)
			(size 0.59 0.64)
			(layers "B.Cu" "B.Mask" "B.Paste")
			(roundrect_rratio 0.25)
			(net 1 "GND")
			(pintype "passive")
		)
	)
	(footprint "antmicro-footprints:C_0402_1005Metric"
		(layer "B.Cu")
		(at 132.624499 138.732157 90)
		(descr "Capacitor SMD 0402")
		(tags "capacitor SMD 0402")
		(property "Reference" "C136"
			(at 1.176157 0.344672 90)
			(layer "B.SilkS")
			(effects
				(font
					(size 0.7 0.7)
					(thickness 0.15)
				)
				(justify right bottom mirror)
			)
		)
		(property "Value" "C_10n_0402"
			(at -1.022927 -2.155213 90)
			(layer "B.Fab")
			(effects
				(font
					(size 0.7 0.7)
					(thickness 0.15)
				)
				(justify right bottom mirror)
			)
		)
		(property "Datasheet" "https://www.murata.com/products/productdetail?partno=GRM155R71H103KA88%23"
			(at 0 0 90)
			(layer "F.Fab")
			(hide yes)
			(effects
				(font
					(size 1.27 1.27)
					(thickness 0.15)
				)
			)
		)
		(property "Manufacturer" "Murata"
			(at 0 0 90)
			(unlocked yes)
			(layer "B.Fab")
			(hide yes)
			(effects
				(font
					(size 1 1)
					(thickness 0.15)
				)
				(justify mirror)
			)
		)
		(property "MPN" "GRM155R71H103KA88D"
			(at 0 0 90)
			(unlocked yes)
			(layer "B.Fab")
			(hide yes)
			(effects
				(font
					(size 1 1)
					(thickness 0.15)
				)
				(justify mirror)
			)
		)
		(property "Val" "10n"
			(at 0 0 90)
			(unlocked yes)
			(layer "B.Fab")
			(hide yes)
			(effects
				(font
					(size 1 1)
					(thickness 0.15)
				)
				(justify mirror)
			)
		)
		(property "License" "Apache-2.0"
			(at 0 0 90)
			(unlocked yes)
			(layer "B.Fab")
			(hide yes)
			(effects
				(font
					(size 1 1)
					(thickness 0.15)
				)
				(justify mirror)
			)
		)
		(property "Author" "Antmicro"
			(at 0 0 90)
			(unlocked yes)
			(layer "B.Fab")
			(hide yes)
			(effects
				(font
					(size 1 1)
					(thickness 0.15)
				)
				(justify mirror)
			)
		)
		(property "Voltage" "50V"
			(at 0 0 90)
			(unlocked yes)
			(layer "B.Fab")
			(hide yes)
			(effects
				(font
					(size 1 1)
					(thickness 0.15)
				)
				(justify mirror)
			)
		)
		(property "Dielectric" "X7R"
			(at 0 0 90)
			(unlocked yes)
			(layer "B.Fab")
			(hide yes)
			(effects
				(font
					(size 1 1)
					(thickness 0.15)
				)
				(justify mirror)
			)
		)
		(sheetname "/Ethernet/")
		(sheetfile "ethernet.kicad_sch")
		(attr smd)
		(fp_rect
			(start -0.925 0.47)
			(end 0.925 -0.47)
			(stroke
				(width 0.05)
				(type default)
			)
			(fill no)
			(layer "B.CrtYd")
		)
		(fp_line
			(start 0.504 -0.248)
			(end -0.494 -0.248)
			(stroke
				(width 0.15)
				(type solid)
			)
			(layer "B.Fab")
		)
		(fp_line
			(start -0.494 -0.248)
			(end -0.494 0.25)
			(stroke
				(width 0.15)
				(type solid)
			)
			(layer "B.Fab")
		)
		(fp_line
			(start 0.504 0.25)
			(end 0.504 -0.248)
			(stroke
				(width 0.15)
				(type solid)
			)
			(layer "B.Fab")
		)
		(fp_line
			(start -0.494 0.25)
			(end 0.504 0.25)
			(stroke
				(width 0.15)
				(type solid)
			)
			(layer "B.Fab")
		)
		(fp_text user "${REFERENCE}"
			(at -0.939 -4.599 270)
			(layer "B.Fab")
			(effects
				(font
					(size 0.7 0.7)
					(thickness 0.15)
				)
				(justify left bottom mirror)
			)
		)
		(fp_text user "License: Apache-2.0"
			(at -0.939 -5.799 270)
			(layer "B.Fab")
			(effects
				(font
					(size 0.7 0.7)
					(thickness 0.15)
				)
				(justify left bottom mirror)
			)
		)
		(fp_text user "Author: Antmicro"
			(at -0.939 -3.399 270)
			(layer "B.Fab")
			(effects
				(font
					(size 0.7 0.7)
					(thickness 0.15)
				)
				(justify left bottom mirror)
			)
		)
		(pad "1" smd roundrect
			(at -0.48 0 90)
			(size 0.59 0.64)
			(layers "B.Cu" "B.Mask" "B.Paste")
			(roundrect_rratio 0.25)
			(net 95 "/Ethernet/AVDDL")
			(pintype "passive")
		)
		(pad "2" smd roundrect
			(at 0.48 0 90)
			(size 0.59 0.64)
			(layers "B.Cu" "B.Mask" "B.Paste")
			(roundrect_rratio 0.25)
			(net 1 "GND")
			(pintype "passive")
		)
	)
	(footprint "antmicro-footprints:C_0402_1005Metric"
		(layer "B.Cu")
		(at 139.224499 143.649)
		(descr "Capacitor SMD 0402")
		(tags "capacitor SMD 0402")
		(property "Reference" "C144"
			(at 0.983501 0.623 0)
			(layer "B.SilkS")
			(effects
				(font
					(size 0.7 0.7)
					(thickness 0.15)
				)
				(justify right bottom mirror)
			)
		)
		(property "Value" "C_10n_0402"
			(at -1.022927 -2.155213 0)
			(layer "B.Fab")
			(effects
				(font
					(size 0.7 0.7)
					(thickness 0.15)
				)
				(justify right bottom mirror)
			)
		)
		(property "Datasheet" "https://www.murata.com/products/productdetail?partno=GRM155R71H103KA88%23"
			(at 0 0 0)
			(layer "F.Fab")
			(hide yes)
			(effects
				(font
					(size 1.27 1.27)
					(thickness 0.15)
				)
			)
		)
		(property "Manufacturer" "Murata"
			(at 0 0 0)
			(unlocked yes)
			(layer "B.Fab")
			(hide yes)
			(effects
				(font
					(size 1 1)
					(thickness 0.15)
				)
				(justify mirror)
			)
		)
		(property "MPN" "GRM155R71H103KA88D"
			(at 0 0 0)
			(unlocked yes)
			(layer "B.Fab")
			(hide yes)
			(effects
				(font
					(size 1 1)
					(thickness 0.15)
				)
				(justify mirror)
			)
		)
		(property "Val" "10n"
			(at 0 0 0)
			(unlocked yes)
			(layer "B.Fab")
			(hide yes)
			(effects
				(font
					(size 1 1)
					(thickness 0.15)
				)
				(justify mirror)
			)
		)
		(property "License" "Apache-2.0"
			(at 0 0 0)
			(unlocked yes)
			(layer "B.Fab")
			(hide yes)
			(effects
				(font
					(size 1 1)
					(thickness 0.15)
				)
				(justify mirror)
			)
		)
		(property "Author" "Antmicro"
			(at 0 0 0)
			(unlocked yes)
			(layer "B.Fab")
			(hide yes)
			(effects
				(font
					(size 1 1)
					(thickness 0.15)
				)
				(justify mirror)
			)
		)
		(property "Voltage" "50V"
			(at 0 0 0)
			(unlocked yes)
			(layer "B.Fab")
			(hide yes)
			(effects
				(font
					(size 1 1)
					(thickness 0.15)
				)
				(justify mirror)
			)
		)
		(property "Dielectric" "X7R"
			(at 0 0 0)
			(unlocked yes)
			(layer "B.Fab")
			(hide yes)
			(effects
				(font
					(size 1 1)
					(thickness 0.15)
				)
				(justify mirror)
			)
		)
		(sheetname "/Ethernet/")
		(sheetfile "ethernet.kicad_sch")
		(attr smd)
		(fp_rect
			(start -0.925 0.47)
			(end 0.925 -0.47)
			(stroke
				(width 0.05)
				(type default)
			)
			(fill no)
			(layer "B.CrtYd")
		)
		(fp_line
			(start -0.494 -0.248)
			(end -0.494 0.25)
			(stroke
				(width 0.15)
				(type solid)
			)
			(layer "B.Fab")
		)
		(fp_line
			(start -0.494 0.25)
			(end 0.504 0.25)
			(stroke
				(width 0.15)
				(type solid)
			)
			(layer "B.Fab")
		)
		(fp_line
			(start 0.504 -0.248)
			(end -0.494 -0.248)
			(stroke
				(width 0.15)
				(type solid)
			)
			(layer "B.Fab")
		)
		(fp_line
			(start 0.504 0.25)
			(end 0.504 -0.248)
			(stroke
				(width 0.15)
				(type solid)
			)
			(layer "B.Fab")
		)
		(fp_text user "Author: Antmicro"
			(at -0.939 -3.399 180)
			(layer "B.Fab")
			(effects
				(font
					(size 0.7 0.7)
					(thickness 0.15)
				)
				(justify left bottom mirror)
			)
		)
		(fp_text user "${REFERENCE}"
			(at -0.939 -4.599 180)
			(layer "B.Fab")
			(effects
				(font
					(size 0.7 0.7)
					(thickness 0.15)
				)
				(justify left bottom mirror)
			)
		)
		(fp_text user "License: Apache-2.0"
			(at -0.939 -5.799 180)
			(layer "B.Fab")
			(effects
				(font
					(size 0.7 0.7)
					(thickness 0.15)
				)
				(justify left bottom mirror)
			)
		)
		(pad "1" smd roundrect
			(at -0.48 0)
			(size 0.59 0.64)
			(layers "B.Cu" "B.Mask" "B.Paste")
			(roundrect_rratio 0.25)
			(net 797 "+1V8")
			(pintype "passive")
		)
		(pad "2" smd roundrect
			(at 0.48 0)
			(size 0.59 0.64)
			(layers "B.Cu" "B.Mask" "B.Paste")
			(roundrect_rratio 0.25)
			(net 1 "GND")
			(pintype "passive")
		)
	)
	(footprint "antmicro-footprints:C_0402_1005Metric"
		(layer "B.Cu")
		(at 131.211328 138.082157 90)
		(descr "Capacitor SMD 0402")
		(tags "capacitor SMD 0402")
		(property "Reference" "C155"
			(at 1.176157 0.344672 90)
			(layer "B.SilkS")
			(effects
				(font
					(size 0.7 0.7)
					(thickness 0.15)
				)
				(justify right bottom mirror)
			)
		)
		(property "Value" "C_4u7_0402"
			(at -1.022927 -2.155213 90)
			(layer "B.Fab")
			(effects
				(font
					(size 0.7 0.7)
					(thickness 0.15)
				)
				(justify right bottom mirror)
			)
		)
		(property "Datasheet" "https://www.murata.com/products/productdetail?partno=GRM155R61A475MEAA%23"
			(at 0 0 90)
			(layer "F.Fab")
			(hide yes)
			(effects
				(font
					(size 1.27 1.27)
					(thickness 0.15)
				)
			)
		)
		(property "Manufacturer" "Murata"
			(at 0 0 90)
			(unlocked yes)
			(layer "B.Fab")
			(hide yes)
			(effects
				(font
					(size 1 1)
					(thickness 0.15)
				)
				(justify mirror)
			)
		)
		(property "MPN" "GRM155R61A475MEAAD"
			(at 0 0 90)
			(unlocked yes)
			(layer "B.Fab")
			(hide yes)
			(effects
				(font
					(size 1 1)
					(thickness 0.15)
				)
				(justify mirror)
			)
		)
		(property "Val" "4u7"
			(at 0 0 90)
			(unlocked yes)
			(layer "B.Fab")
			(hide yes)
			(effects
				(font
					(size 1 1)
					(thickness 0.15)
				)
				(justify mirror)
			)
		)
		(property "License" "Apache-2.0"
			(at 0 0 90)
			(unlocked yes)
			(layer "B.Fab")
			(hide yes)
			(effects
				(font
					(size 1 1)
					(thickness 0.15)
				)
				(justify mirror)
			)
		)
		(property "Author" "Antmicro"
			(at 0 0 90)
			(unlocked yes)
			(layer "B.Fab")
			(hide yes)
			(effects
				(font
					(size 1 1)
					(thickness 0.15)
				)
				(justify mirror)
			)
		)
		(property "Voltage" ""
			(at 0 0 90)
			(unlocked yes)
			(layer "B.Fab")
			(hide yes)
			(effects
				(font
					(size 1 1)
					(thickness 0.15)
				)
				(justify mirror)
			)
		)
		(property "Dielectric" ""
			(at 0 0 90)
			(unlocked yes)
			(layer "B.Fab")
			(hide yes)
			(effects
				(font
					(size 1 1)
					(thickness 0.15)
				)
				(justify mirror)
			)
		)
		(sheetname "/Ethernet/")
		(sheetfile "ethernet.kicad_sch")
		(attr smd)
		(fp_rect
			(start -0.925 0.47)
			(end 0.925 -0.47)
			(stroke
				(width 0.05)
				(type default)
			)
			(fill no)
			(layer "B.CrtYd")
		)
		(fp_line
			(start 0.504 -0.248)
			(end -0.494 -0.248)
			(stroke
				(width 0.15)
				(type solid)
			)
			(layer "B.Fab")
		)
		(fp_line
			(start -0.494 -0.248)
			(end -0.494 0.25)
			(stroke
				(width 0.15)
				(type solid)
			)
			(layer "B.Fab")
		)
		(fp_line
			(start 0.504 0.25)
			(end 0.504 -0.248)
			(stroke
				(width 0.15)
				(type solid)
			)
			(layer "B.Fab")
		)
		(fp_line
			(start -0.494 0.25)
			(end 0.504 0.25)
			(stroke
				(width 0.15)
				(type solid)
			)
			(layer "B.Fab")
		)
		(fp_text user "${REFERENCE}"
			(at -0.939 -4.599 270)
			(layer "B.Fab")
			(effects
				(font
					(size 0.7 0.7)
					(thickness 0.15)
				)
				(justify left bottom mirror)
			)
		)
		(fp_text user "Author: Antmicro"
			(at -0.939 -3.399 270)
			(layer "B.Fab")
			(effects
				(font
					(size 0.7 0.7)
					(thickness 0.15)
				)
				(justify left bottom mirror)
			)
		)
		(fp_text user "License: Apache-2.0"
			(at -0.939 -5.799 270)
			(layer "B.Fab")
			(effects
				(font
					(size 0.7 0.7)
					(thickness 0.15)
				)
				(justify left bottom mirror)
			)
		)
		(pad "1" smd roundrect
			(at -0.48 0 90)
			(size 0.59 0.64)
			(layers "B.Cu" "B.Mask" "B.Paste")
			(roundrect_rratio 0.25)
			(net 97 "/Ethernet/AVDDH")
			(pintype "passive")
		)
		(pad "2" smd roundrect
			(at 0.48 0 90)
			(size 0.59 0.64)
			(layers "B.Cu" "B.Mask" "B.Paste")
			(roundrect_rratio 0.25)
			(net 1 "GND")
			(pintype "passive")
		)
	)
	(footprint "antmicro-footprints:C_0402_1005Metric"
		(layer "B.Cu")
		(at 133.433171 146.453992 90)
		(descr "Capacitor SMD 0402")
		(tags "capacitor SMD 0402")
		(property "Reference" "C151"
			(at -3.914008 0.202829 90)
			(layer "B.SilkS")
			(effects
				(font
					(size 0.7 0.7)
					(thickness 0.15)
				)
				(justify right bottom mirror)
			)
		)
		(property "Value" "C_10n_0402"
			(at -1.022927 -2.155213 90)
			(layer "B.Fab")
			(effects
				(font
					(size 0.7 0.7)
					(thickness 0.15)
				)
				(justify right bottom mirror)
			)
		)
		(property "Datasheet" "https://www.murata.com/products/productdetail?partno=GRM155R71H103KA88%23"
			(at 0 0 90)
			(layer "F.Fab")
			(hide yes)
			(effects
				(font
					(size 1.27 1.27)
					(thickness 0.15)
				)
			)
		)
		(property "Manufacturer" "Murata"
			(at 0 0 90)
			(unlocked yes)
			(layer "B.Fab")
			(hide yes)
			(effects
				(font
					(size 1 1)
					(thickness 0.15)
				)
				(justify mirror)
			)
		)
		(property "MPN" "GRM155R71H103KA88D"
			(at 0 0 90)
			(unlocked yes)
			(layer "B.Fab")
			(hide yes)
			(effects
				(font
					(size 1 1)
					(thickness 0.15)
				)
				(justify mirror)
			)
		)
		(property "Val" "10n"
			(at 0 0 90)
			(unlocked yes)
			(layer "B.Fab")
			(hide yes)
			(effects
				(font
					(size 1 1)
					(thickness 0.15)
				)
				(justify mirror)
			)
		)
		(property "License" "Apache-2.0"
			(at 0 0 90)
			(unlocked yes)
			(layer "B.Fab")
			(hide yes)
			(effects
				(font
					(size 1 1)
					(thickness 0.15)
				)
				(justify mirror)
			)
		)
		(property "Author" "Antmicro"
			(at 0 0 90)
			(unlocked yes)
			(layer "B.Fab")
			(hide yes)
			(effects
				(font
					(size 1 1)
					(thickness 0.15)
				)
				(justify mirror)
			)
		)
		(property "Voltage" "50V"
			(at 0 0 90)
			(unlocked yes)
			(layer "B.Fab")
			(hide yes)
			(effects
				(font
					(size 1 1)
					(thickness 0.15)
				)
				(justify mirror)
			)
		)
		(property "Dielectric" "X7R"
			(at 0 0 90)
			(unlocked yes)
			(layer "B.Fab")
			(hide yes)
			(effects
				(font
					(size 1 1)
					(thickness 0.15)
				)
				(justify mirror)
			)
		)
		(sheetname "/Ethernet/")
		(sheetfile "ethernet.kicad_sch")
		(attr smd)
		(fp_rect
			(start -0.925 0.47)
			(end 0.925 -0.47)
			(stroke
				(width 0.05)
				(type default)
			)
			(fill no)
			(layer "B.CrtYd")
		)
		(fp_line
			(start 0.504 -0.248)
			(end -0.494 -0.248)
			(stroke
				(width 0.15)
				(type solid)
			)
			(layer "B.Fab")
		)
		(fp_line
			(start -0.494 -0.248)
			(end -0.494 0.25)
			(stroke
				(width 0.15)
				(type solid)
			)
			(layer "B.Fab")
		)
		(fp_line
			(start 0.504 0.25)
			(end 0.504 -0.248)
			(stroke
				(width 0.15)
				(type solid)
			)
			(layer "B.Fab")
		)
		(fp_line
			(start -0.494 0.25)
			(end 0.504 0.25)
			(stroke
				(width 0.15)
				(type solid)
			)
			(layer "B.Fab")
		)
		(fp_text user "License: Apache-2.0"
			(at -0.939 -5.799 270)
			(layer "B.Fab")
			(effects
				(font
					(size 0.7 0.7)
					(thickness 0.15)
				)
				(justify left bottom mirror)
			)
		)
		(fp_text user "Author: Antmicro"
			(at -0.939 -3.399 270)
			(layer "B.Fab")
			(effects
				(font
					(size 0.7 0.7)
					(thickness 0.15)
				)
				(justify left bottom mirror)
			)
		)
		(fp_text user "${REFERENCE}"
			(at -0.939 -4.599 270)
			(layer "B.Fab")
			(effects
				(font
					(size 0.7 0.7)
					(thickness 0.15)
				)
				(justify left bottom mirror)
			)
		)
		(pad "1" smd roundrect
			(at -0.48 0 90)
			(size 0.59 0.64)
			(layers "B.Cu" "B.Mask" "B.Paste")
			(roundrect_rratio 0.25)
			(net 150 "+1V2")
			(pintype "passive")
		)
		(pad "2" smd roundrect
			(at 0.48 0 90)
			(size 0.59 0.64)
			(layers "B.Cu" "B.Mask" "B.Paste")
			(roundrect_rratio 0.25)
			(net 1 "GND")
			(pintype "passive")
		)
	)
)
